# S9S_MB_2U (Grand Teton) — schematic parts with pin connectivity, parts 620–722 of 6093; source: Cadence DE-HDL packaged netlist (pstxprt.dat, pstxnet.dat, pstchip.dat)

C773  Q_CAP_DIFFBUS  DIFF BUS_0.22UF 6.3V 20% X6S  pkg C0201  page 176 : 1 = P5E_CPU1_PE2_TX_C_DP<0> ; 2 = P5E_CPU1_PE2_TX_DP<0>
C806  Q_CAP_DIFFBUS  DIFF BUS_0.22UF 6.3V 20% X6S  pkg C0201  page 175 : 1 = P5E_CPU1_PE1_TX_C_DN<15> ; 2 = P5E_CPU1_PE1_TX_DN<15>
C807  Q_CAP_DIFFBUS  DIFF BUS_0.22UF 6.3V 20% X6S  pkg C0201  page 175 : 1 = P5E_CPU1_PE1_TX_C_DP<15> ; 2 = P5E_CPU1_PE1_TX_DP<15>
C808  Q_CAP_DIFFBUS  DIFF BUS_0.22UF 6.3V 20% X6S  pkg C0201  page 175 : 1 = P5E_CPU1_PE1_TX_C_DN<14> ; 2 = P5E_CPU1_PE1_TX_DN<14>
C809  Q_CAP_DIFFBUS  DIFF BUS_0.22UF 6.3V 20% X6S  pkg C0201  page 175 : 1 = P5E_CPU1_PE1_TX_C_DP<14> ; 2 = P5E_CPU1_PE1_TX_DP<14>
C810  Q_CAP_DIFFBUS  DIFF BUS_0.22UF 6.3V 20% X6S  pkg C0201  page 175 : 1 = P5E_CPU1_PE1_TX_C_DN<13> ; 2 = P5E_CPU1_PE1_TX_DN<13>
C811  Q_CAP_DIFFBUS  DIFF BUS_0.22UF 6.3V 20% X6S  pkg C0201  page 175 : 1 = P5E_CPU1_PE1_TX_C_DP<13> ; 2 = P5E_CPU1_PE1_TX_DP<13>
C812  Q_CAP_DIFFBUS  DIFF BUS_0.22UF 6.3V 20% X6S  pkg C0201  page 175 : 1 = P5E_CPU1_PE1_TX_C_DN<12> ; 2 = P5E_CPU1_PE1_TX_DN<12>
C813  Q_CAP_DIFFBUS  DIFF BUS_0.22UF 6.3V 20% X6S  pkg C0201  page 175 : 1 = P5E_CPU1_PE1_TX_C_DP<12> ; 2 = P5E_CPU1_PE1_TX_DP<12>
C814  Q_CAP_DIFFBUS  DIFF BUS_0.22UF 6.3V 20% X6S  pkg C0201  page 175 : 1 = P5E_CPU1_PE1_TX_C_DN<11> ; 2 = P5E_CPU1_PE1_TX_DN<11>
C815  Q_CAP_DIFFBUS  DIFF BUS_0.22UF 6.3V 20% X6S  pkg C0201  page 175 : 1 = P5E_CPU1_PE1_TX_C_DP<11> ; 2 = P5E_CPU1_PE1_TX_DP<11>
C816  Q_CAP_DIFFBUS  DIFF BUS_0.22UF 6.3V 20% X6S  pkg C0201  page 175 : 1 = P5E_CPU1_PE1_TX_C_DN<10> ; 2 = P5E_CPU1_PE1_TX_DN<10>
C817  Q_CAP_DIFFBUS  DIFF BUS_0.22UF 6.3V 20% X6S  pkg C0201  page 175 : 1 = P5E_CPU1_PE1_TX_C_DP<10> ; 2 = P5E_CPU1_PE1_TX_DP<10>
C818  Q_CAP_DIFFBUS  DIFF BUS_0.22UF 6.3V 20% X6S  pkg C0201  page 175 : 1 = P5E_CPU1_PE1_TX_C_DN<9> ; 2 = P5E_CPU1_PE1_TX_DN<9>
C819  Q_CAP_DIFFBUS  DIFF BUS_0.22UF 6.3V 20% X6S  pkg C0201  page 175 : 1 = P5E_CPU1_PE1_TX_C_DP<9> ; 2 = P5E_CPU1_PE1_TX_DP<9>
C820  Q_CAP_DIFFBUS  DIFF BUS_0.22UF 6.3V 20% X6S  pkg C0201  page 175 : 1 = P5E_CPU1_PE1_TX_C_DN<8> ; 2 = P5E_CPU1_PE1_TX_DN<8>
C821  Q_CAP_DIFFBUS  DIFF BUS_0.22UF 6.3V 20% X6S  pkg C0201  page 175 : 1 = P5E_CPU1_PE1_TX_C_DP<8> ; 2 = P5E_CPU1_PE1_TX_DP<8>
C822  Q_CAP_DIFFBUS  DIFF BUS_0.22UF 6.3V 20% X6S  pkg C0201  page 175 : 1 = P5E_CPU1_PE1_TX_C_DN<7> ; 2 = P5E_CPU1_PE1_TX_DN<7>
C823  Q_CAP_DIFFBUS  DIFF BUS_0.22UF 6.3V 20% X6S  pkg C0201  page 175 : 1 = P5E_CPU1_PE1_TX_C_DP<7> ; 2 = P5E_CPU1_PE1_TX_DP<7>
C824  Q_CAP_DIFFBUS  DIFF BUS_0.22UF 6.3V 20% X6S  pkg C0201  page 175 : 1 = P5E_CPU1_PE1_TX_C_DN<6> ; 2 = P5E_CPU1_PE1_TX_DN<6>
C825  Q_CAP_DIFFBUS  DIFF BUS_0.22UF 6.3V 20% X6S  pkg C0201  page 175 : 1 = P5E_CPU1_PE1_TX_C_DP<6> ; 2 = P5E_CPU1_PE1_TX_DP<6>
C826  Q_CAP_DIFFBUS  DIFF BUS_0.22UF 6.3V 20% X6S  pkg C0201  page 175 : 1 = P5E_CPU1_PE1_TX_C_DN<5> ; 2 = P5E_CPU1_PE1_TX_DN<5>
C827  Q_CAP_DIFFBUS  DIFF BUS_0.22UF 6.3V 20% X6S  pkg C0201  page 175 : 1 = P5E_CPU1_PE1_TX_C_DP<5> ; 2 = P5E_CPU1_PE1_TX_DP<5>
C828  Q_CAP_DIFFBUS  DIFF BUS_0.22UF 6.3V 20% X6S  pkg C0201  page 175 : 1 = P5E_CPU1_PE1_TX_C_DN<4> ; 2 = P5E_CPU1_PE1_TX_DN<4>
C829  Q_CAP_DIFFBUS  DIFF BUS_0.22UF 6.3V 20% X6S  pkg C0201  page 175 : 1 = P5E_CPU1_PE1_TX_C_DP<4> ; 2 = P5E_CPU1_PE1_TX_DP<4>
C830  Q_CAP_DIFFBUS  DIFF BUS_0.22UF 6.3V 20% X6S  pkg C0201  page 175 : 1 = P5E_CPU1_PE1_TX_C_DN<3> ; 2 = P5E_CPU1_PE1_TX_DN<3>
C831  Q_CAP_DIFFBUS  DIFF BUS_0.22UF 6.3V 20% X6S  pkg C0201  page 175 : 1 = P5E_CPU1_PE1_TX_C_DP<3> ; 2 = P5E_CPU1_PE1_TX_DP<3>
C832  Q_CAP_DIFFBUS  DIFF BUS_0.22UF 6.3V 20% X6S  pkg C0201  page 175 : 1 = P5E_CPU1_PE1_TX_C_DN<2> ; 2 = P5E_CPU1_PE1_TX_DN<2>
C833  Q_CAP_DIFFBUS  DIFF BUS_0.22UF 6.3V 20% X6S  pkg C0201  page 175 : 1 = P5E_CPU1_PE1_TX_C_DP<2> ; 2 = P5E_CPU1_PE1_TX_DP<2>
C834  Q_CAP_DIFFBUS  DIFF BUS_0.22UF 6.3V 20% X6S  pkg C0201  page 175 : 1 = P5E_CPU1_PE1_TX_C_DN<1> ; 2 = P5E_CPU1_PE1_TX_DN<1>
C835  Q_CAP_DIFFBUS  DIFF BUS_0.22UF 6.3V 20% X6S  pkg C0201  page 175 : 1 = P5E_CPU1_PE1_TX_C_DP<1> ; 2 = P5E_CPU1_PE1_TX_DP<1>
C836  Q_CAP_DIFFBUS  DIFF BUS_0.22UF 6.3V 20% X6S  pkg C0201  page 175 : 1 = P5E_CPU1_PE1_TX_C_DN<0> ; 2 = P5E_CPU1_PE1_TX_DN<0>
C837  Q_CAP_DIFFBUS  DIFF BUS_0.22UF 6.3V 20% X6S  pkg C0201  page 175 : 1 = P5E_CPU1_PE1_TX_C_DP<0> ; 2 = P5E_CPU1_PE1_TX_DP<0>
C838  Q_CAP_DIFFBUS  DIFF BUS_0.22UF 6.3V 20% X6S  pkg C0201  page 174 : 1 = P5E_CPU0_PE1_TX_C_DN<15> ; 2 = P5E_CPU0_PE1_TX_DN<15>
C839  Q_CAP_DIFFBUS  DIFF BUS_0.22UF 6.3V 20% X6S  pkg C0201  page 174 : 1 = P5E_CPU0_PE1_TX_C_DP<15> ; 2 = P5E_CPU0_PE1_TX_DP<15>
C840  Q_CAP_DIFFBUS  DIFF BUS_0.22UF 6.3V 20% X6S  pkg C0201  page 174 : 1 = P5E_CPU0_PE1_TX_C_DN<14> ; 2 = P5E_CPU0_PE1_TX_DN<14>
C841  Q_CAP_DIFFBUS  DIFF BUS_0.22UF 6.3V 20% X6S  pkg C0201  page 174 : 1 = P5E_CPU0_PE1_TX_C_DP<14> ; 2 = P5E_CPU0_PE1_TX_DP<14>
C842  Q_CAP_DIFFBUS  DIFF BUS_0.22UF 6.3V 20% X6S  pkg C0201  page 174 : 1 = P5E_CPU0_PE1_TX_C_DN<13> ; 2 = P5E_CPU0_PE1_TX_DN<13>
C843  Q_CAP_DIFFBUS  DIFF BUS_0.22UF 6.3V 20% X6S  pkg C0201  page 174 : 1 = P5E_CPU0_PE1_TX_C_DP<13> ; 2 = P5E_CPU0_PE1_TX_DP<13>
C844  Q_CAP_DIFFBUS  DIFF BUS_0.22UF 6.3V 20% X6S  pkg C0201  page 174 : 1 = P5E_CPU0_PE1_TX_C_DN<12> ; 2 = P5E_CPU0_PE1_TX_DN<12>
C845  Q_CAP_DIFFBUS  DIFF BUS_0.22UF 6.3V 20% X6S  pkg C0201  page 174 : 1 = P5E_CPU0_PE1_TX_C_DP<12> ; 2 = P5E_CPU0_PE1_TX_DP<12>
C846  Q_CAP_DIFFBUS  DIFF BUS_0.22UF 6.3V 20% X6S  pkg C0201  page 174 : 1 = P5E_CPU0_PE1_TX_C_DN<11> ; 2 = P5E_CPU0_PE1_TX_DN<11>
C847  Q_CAP_DIFFBUS  DIFF BUS_0.22UF 6.3V 20% X6S  pkg C0201  page 174 : 1 = P5E_CPU0_PE1_TX_C_DP<11> ; 2 = P5E_CPU0_PE1_TX_DP<11>
C848  Q_CAP_DIFFBUS  DIFF BUS_0.22UF 6.3V 20% X6S  pkg C0201  page 174 : 1 = P5E_CPU0_PE1_TX_C_DN<10> ; 2 = P5E_CPU0_PE1_TX_DN<10>
C849  Q_CAP_DIFFBUS  DIFF BUS_0.22UF 6.3V 20% X6S  pkg C0201  page 174 : 1 = P5E_CPU0_PE1_TX_C_DP<10> ; 2 = P5E_CPU0_PE1_TX_DP<10>
C850  Q_CAP_DIFFBUS  DIFF BUS_0.22UF 6.3V 20% X6S  pkg C0201  page 174 : 1 = P5E_CPU0_PE1_TX_C_DN<9> ; 2 = P5E_CPU0_PE1_TX_DN<9>
C851  Q_CAP_DIFFBUS  DIFF BUS_0.22UF 6.3V 20% X6S  pkg C0201  page 174 : 1 = P5E_CPU0_PE1_TX_C_DP<9> ; 2 = P5E_CPU0_PE1_TX_DP<9>
C852  Q_CAP_DIFFBUS  DIFF BUS_0.22UF 6.3V 20% X6S  pkg C0201  page 174 : 1 = P5E_CPU0_PE1_TX_C_DN<8> ; 2 = P5E_CPU0_PE1_TX_DN<8>
C853  Q_CAP_DIFFBUS  DIFF BUS_0.22UF 6.3V 20% X6S  pkg C0201  page 174 : 1 = P5E_CPU0_PE1_TX_C_DP<8> ; 2 = P5E_CPU0_PE1_TX_DP<8>
C854  Q_CAP_DIFFBUS  DIFF BUS_0.22UF 6.3V 20% X6S  pkg C0201  page 174 : 1 = P5E_CPU0_PE1_TX_C_DN<7> ; 2 = P5E_CPU0_PE1_TX_DN<7>
C855  Q_CAP_DIFFBUS  DIFF BUS_0.22UF 6.3V 20% X6S  pkg C0201  page 174 : 1 = P5E_CPU0_PE1_TX_C_DP<7> ; 2 = P5E_CPU0_PE1_TX_DP<7>
C856  Q_CAP_DIFFBUS  DIFF BUS_0.22UF 6.3V 20% X6S  pkg C0201  page 174 : 1 = P5E_CPU0_PE1_TX_C_DN<6> ; 2 = P5E_CPU0_PE1_TX_DN<6>
C857  Q_CAP_DIFFBUS  DIFF BUS_0.22UF 6.3V 20% X6S  pkg C0201  page 174 : 1 = P5E_CPU0_PE1_TX_C_DP<6> ; 2 = P5E_CPU0_PE1_TX_DP<6>
C858  Q_CAP_DIFFBUS  DIFF BUS_0.22UF 6.3V 20% X6S  pkg C0201  page 174 : 1 = P5E_CPU0_PE1_TX_C_DN<5> ; 2 = P5E_CPU0_PE1_TX_DN<5>
C859  Q_CAP_DIFFBUS  DIFF BUS_0.22UF 6.3V 20% X6S  pkg C0201  page 174 : 1 = P5E_CPU0_PE1_TX_C_DP<5> ; 2 = P5E_CPU0_PE1_TX_DP<5>
C860  Q_CAP_DIFFBUS  DIFF BUS_0.22UF 6.3V 20% X6S  pkg C0201  page 174 : 1 = P5E_CPU0_PE1_TX_C_DN<4> ; 2 = P5E_CPU0_PE1_TX_DN<4>
C861  Q_CAP_DIFFBUS  DIFF BUS_0.22UF 6.3V 20% X6S  pkg C0201  page 174 : 1 = P5E_CPU0_PE1_TX_C_DP<4> ; 2 = P5E_CPU0_PE1_TX_DP<4>
C862  Q_CAP_DIFFBUS  DIFF BUS_0.22UF 6.3V 20% X6S  pkg C0201  page 174 : 1 = P5E_CPU0_PE1_TX_C_DN<3> ; 2 = P5E_CPU0_PE1_TX_DN<3>
C863  Q_CAP_DIFFBUS  DIFF BUS_0.22UF 6.3V 20% X6S  pkg C0201  page 174 : 1 = P5E_CPU0_PE1_TX_C_DP<3> ; 2 = P5E_CPU0_PE1_TX_DP<3>
C864  Q_CAP_DIFFBUS  DIFF BUS_0.22UF 6.3V 20% X6S  pkg C0201  page 174 : 1 = P5E_CPU0_PE1_TX_C_DN<2> ; 2 = P5E_CPU0_PE1_TX_DN<2>
C865  Q_CAP_DIFFBUS  DIFF BUS_0.22UF 6.3V 20% X6S  pkg C0201  page 174 : 1 = P5E_CPU0_PE1_TX_C_DP<2> ; 2 = P5E_CPU0_PE1_TX_DP<2>
C866  Q_CAP_DIFFBUS  DIFF BUS_0.22UF 6.3V 20% X6S  pkg C0201  page 174 : 1 = P5E_CPU0_PE1_TX_C_DN<1> ; 2 = P5E_CPU0_PE1_TX_DN<1>
C867  Q_CAP_DIFFBUS  DIFF BUS_0.22UF 6.3V 20% X6S  pkg C0201  page 174 : 1 = P5E_CPU0_PE1_TX_C_DP<1> ; 2 = P5E_CPU0_PE1_TX_DP<1>
C868  Q_CAP_DIFFBUS  DIFF BUS_0.22UF 6.3V 20% X6S  pkg C0201  page 174 : 1 = P5E_CPU0_PE1_TX_C_DN<0> ; 2 = P5E_CPU0_PE1_TX_DN<0>
C869  Q_CAP_DIFFBUS  DIFF BUS_0.22UF 6.3V 20% X6S  pkg C0201  page 174 : 1 = P5E_CPU0_PE1_TX_C_DP<0> ; 2 = P5E_CPU0_PE1_TX_DP<0>
C870  Q_CAP_DIFFBUS  DIFF BUS_0.22UF 6.3V 20% X6S  pkg C0201  page 174 : 1 = P5E_CPU0_PE3_TX_C_DN<15> ; 2 = P5E_CPU0_PE3_TX_DN<15>
C871  Q_CAP_DIFFBUS  DIFF BUS_0.22UF 6.3V 20% X6S  pkg C0201  page 174 : 1 = P5E_CPU0_PE3_TX_C_DP<15> ; 2 = P5E_CPU0_PE3_TX_DP<15>
C872  Q_CAP_DIFFBUS  DIFF BUS_0.22UF 6.3V 20% X6S  pkg C0201  page 174 : 1 = P5E_CPU0_PE3_TX_C_DN<14> ; 2 = P5E_CPU0_PE3_TX_DN<14>
C873  Q_CAP_DIFFBUS  DIFF BUS_0.22UF 6.3V 20% X6S  pkg C0201  page 174 : 1 = P5E_CPU0_PE3_TX_C_DP<14> ; 2 = P5E_CPU0_PE3_TX_DP<14>
C874  Q_CAP_DIFFBUS  DIFF BUS_0.22UF 6.3V 20% X6S  pkg C0201  page 174 : 1 = P5E_CPU0_PE3_TX_C_DN<13> ; 2 = P5E_CPU0_PE3_TX_DN<13>
C875  Q_CAP_DIFFBUS  DIFF BUS_0.22UF 6.3V 20% X6S  pkg C0201  page 174 : 1 = P5E_CPU0_PE3_TX_C_DP<13> ; 2 = P5E_CPU0_PE3_TX_DP<13>
C876  Q_CAP_DIFFBUS  DIFF BUS_0.22UF 6.3V 20% X6S  pkg C0201  page 174 : 1 = P5E_CPU0_PE3_TX_C_DN<12> ; 2 = P5E_CPU0_PE3_TX_DN<12>
C877  Q_CAP_DIFFBUS  DIFF BUS_0.22UF 6.3V 20% X6S  pkg C0201  page 174 : 1 = P5E_CPU0_PE3_TX_C_DP<12> ; 2 = P5E_CPU0_PE3_TX_DP<12>
C878  Q_CAP_DIFFBUS  DIFF BUS_0.22UF 6.3V 20% X6S  pkg C0201  page 174 : 1 = P5E_CPU0_PE3_TX_C_DN<11> ; 2 = P5E_CPU0_PE3_TX_DN<11>
C879  Q_CAP_DIFFBUS  DIFF BUS_0.22UF 6.3V 20% X6S  pkg C0201  page 174 : 1 = P5E_CPU0_PE3_TX_C_DP<11> ; 2 = P5E_CPU0_PE3_TX_DP<11>
C880  Q_CAP_DIFFBUS  DIFF BUS_0.22UF 6.3V 20% X6S  pkg C0201  page 174 : 1 = P5E_CPU0_PE3_TX_C_DN<10> ; 2 = P5E_CPU0_PE3_TX_DN<10>
C881  Q_CAP_DIFFBUS  DIFF BUS_0.22UF 6.3V 20% X6S  pkg C0201  page 174 : 1 = P5E_CPU0_PE3_TX_C_DP<10> ; 2 = P5E_CPU0_PE3_TX_DP<10>
C882  Q_CAP_DIFFBUS  DIFF BUS_0.22UF 6.3V 20% X6S  pkg C0201  page 174 : 1 = P5E_CPU0_PE3_TX_C_DN<9> ; 2 = P5E_CPU0_PE3_TX_DN<9>
C883  Q_CAP_DIFFBUS  DIFF BUS_0.22UF 6.3V 20% X6S  pkg C0201  page 174 : 1 = P5E_CPU0_PE3_TX_C_DP<9> ; 2 = P5E_CPU0_PE3_TX_DP<9>
C884  Q_CAP_DIFFBUS  DIFF BUS_0.22UF 6.3V 20% X6S  pkg C0201  page 174 : 1 = P5E_CPU0_PE3_TX_C_DN<8> ; 2 = P5E_CPU0_PE3_TX_DN<8>
C885  Q_CAP_DIFFBUS  DIFF BUS_0.22UF 6.3V 20% X6S  pkg C0201  page 174 : 1 = P5E_CPU0_PE3_TX_C_DP<8> ; 2 = P5E_CPU0_PE3_TX_DP<8>
C886  Q_CAP_DIFFBUS  DIFF BUS_0.22UF 6.3V 20% X6S  pkg C0201  page 174 : 1 = P5E_CPU0_PE3_TX_C_DN<7> ; 2 = P5E_CPU0_PE3_TX_DN<7>
C887  Q_CAP_DIFFBUS  DIFF BUS_0.22UF 6.3V 20% X6S  pkg C0201  page 174 : 1 = P5E_CPU0_PE3_TX_C_DP<7> ; 2 = P5E_CPU0_PE3_TX_DP<7>
C888  Q_CAP_DIFFBUS  DIFF BUS_0.22UF 6.3V 20% X6S  pkg C0201  page 174 : 1 = P5E_CPU0_PE3_TX_C_DN<6> ; 2 = P5E_CPU0_PE3_TX_DN<6>
C889  Q_CAP_DIFFBUS  DIFF BUS_0.22UF 6.3V 20% X6S  pkg C0201  page 174 : 1 = P5E_CPU0_PE3_TX_C_DP<6> ; 2 = P5E_CPU0_PE3_TX_DP<6>
C890  Q_CAP_DIFFBUS  DIFF BUS_0.22UF 6.3V 20% X6S  pkg C0201  page 174 : 1 = P5E_CPU0_PE3_TX_C_DN<5> ; 2 = P5E_CPU0_PE3_TX_DN<5>
C891  Q_CAP_DIFFBUS  DIFF BUS_0.22UF 6.3V 20% X6S  pkg C0201  page 174 : 1 = P5E_CPU0_PE3_TX_C_DP<5> ; 2 = P5E_CPU0_PE3_TX_DP<5>
C892  Q_CAP_DIFFBUS  DIFF BUS_0.22UF 6.3V 20% X6S  pkg C0201  page 174 : 1 = P5E_CPU0_PE3_TX_C_DN<4> ; 2 = P5E_CPU0_PE3_TX_DN<4>
C893  Q_CAP_DIFFBUS  DIFF BUS_0.22UF 6.3V 20% X6S  pkg C0201  page 174 : 1 = P5E_CPU0_PE3_TX_C_DP<4> ; 2 = P5E_CPU0_PE3_TX_DP<4>
C894  Q_CAP_DIFFBUS  DIFF BUS_0.22UF 6.3V 20% X6S  pkg C0201  page 174 : 1 = P5E_CPU0_PE3_TX_C_DN<3> ; 2 = P5E_CPU0_PE3_TX_DN<3>
C895  Q_CAP_DIFFBUS  DIFF BUS_0.22UF 6.3V 20% X6S  pkg C0201  page 174 : 1 = P5E_CPU0_PE3_TX_C_DP<3> ; 2 = P5E_CPU0_PE3_TX_DP<3>
C896  Q_CAP_DIFFBUS  DIFF BUS_0.22UF 6.3V 20% X6S  pkg C0201  page 174 : 1 = P5E_CPU0_PE3_TX_C_DN<2> ; 2 = P5E_CPU0_PE3_TX_DN<2>
C897  Q_CAP_DIFFBUS  DIFF BUS_0.22UF 6.3V 20% X6S  pkg C0201  page 174 : 1 = P5E_CPU0_PE3_TX_C_DP<2> ; 2 = P5E_CPU0_PE3_TX_DP<2>
C898  Q_CAP_DIFFBUS  DIFF BUS_0.22UF 6.3V 20% X6S  pkg C0201  page 174 : 1 = P5E_CPU0_PE3_TX_C_DN<1> ; 2 = P5E_CPU0_PE3_TX_DN<1>
C899  Q_CAP_DIFFBUS  DIFF BUS_0.22UF 6.3V 20% X6S  pkg C0201  page 174 : 1 = P5E_CPU0_PE3_TX_C_DP<1> ; 2 = P5E_CPU0_PE3_TX_DP<1>
C900  Q_CAP_DIFFBUS  DIFF BUS_0.22UF 6.3V 20% X6S  pkg C0201  page 174 : 1 = P5E_CPU0_PE3_TX_C_DN<0> ; 2 = P5E_CPU0_PE3_TX_DN<0>
C901  Q_CAP_DIFFBUS  DIFF BUS_0.22UF 6.3V 20% X6S  pkg C0201  page 174 : 1 = P5E_CPU0_PE3_TX_C_DP<0> ; 2 = P5E_CPU0_PE3_TX_DP<0>
C902  Q_CAP_DIFFBUS  DIFF BUS_0.22UF 6.3V 20% X6S  pkg C0201  page 173 : 1 = P5E_CPU0_PE0_TX_C_DN<15> ; 2 = P5E_CPU0_PE0_TX_DN<15>
C903  Q_CAP_DIFFBUS  DIFF BUS_0.22UF 6.3V 20% X6S  pkg C0201  page 173 : 1 = P5E_CPU0_PE0_TX_C_DP<15> ; 2 = P5E_CPU0_PE0_TX_DP<15>
C904  Q_CAP_DIFFBUS  DIFF BUS_0.22UF 6.3V 20% X6S  pkg C0201  page 173 : 1 = P5E_CPU0_PE0_TX_C_DN<14> ; 2 = P5E_CPU0_PE0_TX_DN<14>
C905  Q_CAP_DIFFBUS  DIFF BUS_0.22UF 6.3V 20% X6S  pkg C0201  page 173 : 1 = P5E_CPU0_PE0_TX_C_DP<14> ; 2 = P5E_CPU0_PE0_TX_DP<14>
C906  Q_CAP_DIFFBUS  DIFF BUS_0.22UF 6.3V 20% X6S  pkg C0201  page 173 : 1 = P5E_CPU0_PE0_TX_C_DN<13> ; 2 = P5E_CPU0_PE0_TX_DN<13>
C907  Q_CAP_DIFFBUS  DIFF BUS_0.22UF 6.3V 20% X6S  pkg C0201  page 173 : 1 = P5E_CPU0_PE0_TX_C_DP<13> ; 2 = P5E_CPU0_PE0_TX_DP<13>
